(kicad_pcb
	(version 20260206)
	(generator "pcbnew")
	(generator_version "10.0")
	(general
		(thickness 1.6)
		(legacy_teardrops no)
	)
	(paper "A4")
	(title_block
		(title "12092022_DA0F0TMDCD0_F0T_Management_Board_D_brd_V3_OCP.brd")
		(comment 1 "Grand Teton / footprints 612-615 of 1440")
	)
	(layers
		(0 "F.Cu" signal "TOP")
		(4 "In1.Cu" signal "GND")
		(6 "In2.Cu" signal "IN1")
		(8 "In3.Cu" signal "GND1")
		(10 "In4.Cu" signal "IN2")
		(12 "In5.Cu" signal "VCC")
		(14 "In6.Cu" signal "VCC1")
		(16 "In7.Cu" signal "IN3")
		(18 "In8.Cu" signal "GND2")
		(20 "In9.Cu" signal "IN4")
		(22 "In10.Cu" signal "GND3")
		(2 "B.Cu" signal "BOTTOM")
		(9 "F.Adhes" user "F.Adhesive")
		(11 "B.Adhes" user "B.Adhesive")
		(13 "F.Paste" user "Package Geometry/Pastemask Top")
		(15 "B.Paste" user "Package Geometry/Pastemask Bottom")
		(5 "F.SilkS" user "Ref Des/Silkscreen Top")
		(7 "B.SilkS" user "Ref Des/Silkscreen Bottom")
		(1 "F.Mask" user "Board Geometry/Soldermask Top")
		(3 "B.Mask" user "Board Geometry/Soldermask Bottom")
		(17 "Dwgs.User" user "User.Drawings")
		(19 "Cmts.User" user "User.Comments")
		(21 "Eco1.User" user "User.Eco1")
		(23 "Eco2.User" user "User.Eco2")
		(25 "Edge.Cuts" user "Board Geometry/Outline")
		(27 "Margin" user)
		(31 "F.CrtYd" user "Package Geometry/Place Bound Top")
		(29 "B.CrtYd" user "Package Geometry/Place Bound Bottom")
		(35 "F.Fab" user "Ref Des/Assembly Top")
		(33 "B.Fab" user "Ref Des/Assembly Bottom")
	)
	(footprint ""
		(layer "F.Cu")
		(at 38.718236 -38.53561 90)
		(property "Reference" "C30"
			(at 0 0 90)
			(layer "F.SilkS")
			(hide yes)
			(effects
				(font
					(size 1.27 1.27)
				)
			)
		)
		(property "Value" ""
			(at 0 0 90)
			(layer "F.Fab")
			(effects
				(font
					(size 1.27 1.27)
				)
			)
		)
		(duplicate_pad_numbers_are_jumpers no)
		(fp_line
			(start 0.7874 -0.4064)
			(end 0.7874 0.4064)
			(stroke
				(width 0.1524)
				(type default)
			)
			(layer "F.SilkS")
		)
		(fp_line
			(start -0.7874 -0.4064)
			(end 0.7874 -0.4064)
			(stroke
				(width 0.1524)
				(type default)
			)
			(layer "F.SilkS")
		)
		(fp_line
			(start 0.7874 0.4064)
			(end -0.7874 0.4064)
			(stroke
				(width 0.1524)
				(type default)
			)
			(layer "F.SilkS")
		)
		(fp_line
			(start -0.7874 0.4064)
			(end -0.7874 -0.4064)
			(stroke
				(width 0.1524)
				(type default)
			)
			(layer "F.SilkS")
		)
		(fp_line
			(start -0.12065 -0.305054)
			(end -0.12065 -0.2794)
			(stroke
				(width 0.1)
				(type default)
			)
			(layer "F.Fab")
		)
		(fp_line
			(start -0.67945 -0.305054)
			(end -0.12065 -0.305054)
			(stroke
				(width 0.1)
				(type default)
			)
			(layer "F.Fab")
		)
		(fp_line
			(start 0.67945 -0.3048)
			(end 0.67945 0.3048)
			(stroke
				(width 0.1)
				(type default)
			)
			(layer "F.Fab")
		)
		(fp_line
			(start 0.12065 -0.3048)
			(end 0.67945 -0.3048)
			(stroke
				(width 0.1)
				(type default)
			)
			(layer "F.Fab")
		)
		(fp_line
			(start 0.12065 -0.2794)
			(end 0.12065 -0.3048)
			(stroke
				(width 0.1)
				(type default)
			)
			(layer "F.Fab")
		)
		(fp_line
			(start -0.12065 -0.2794)
			(end 0.12065 -0.2794)
			(stroke
				(width 0.1)
				(type default)
			)
			(layer "F.Fab")
		)
		(fp_line
			(start 0.120396 0.2794)
			(end -0.12065 0.2794)
			(stroke
				(width 0.1)
				(type default)
			)
			(layer "F.Fab")
		)
		(fp_line
			(start -0.12065 0.2794)
			(end -0.12065 0.3048)
			(stroke
				(width 0.1)
				(type default)
			)
			(layer "F.Fab")
		)
		(fp_line
			(start 0.67945 0.3048)
			(end 0.120396 0.3048)
			(stroke
				(width 0.1)
				(type default)
			)
			(layer "F.Fab")
		)
		(fp_line
			(start 0.120396 0.3048)
			(end 0.120396 0.2794)
			(stroke
				(width 0.1)
				(type default)
			)
			(layer "F.Fab")
		)
		(fp_line
			(start -0.12065 0.3048)
			(end -0.67945 0.3048)
			(stroke
				(width 0.1)
				(type default)
			)
			(layer "F.Fab")
		)
		(fp_line
			(start -0.67945 0.3048)
			(end -0.67945 -0.305054)
			(stroke
				(width 0.1)
				(type default)
			)
			(layer "F.Fab")
		)
		(pad "1" smd circle
			(at -0.40005 0 90)
			(size 0 0)
			(layers "F.Cu" "F.Mask" "F.Paste")
			(net "P3V3_P2V5_P1V8_RVDD")
		)
		(pad "2" smd circle
			(at 0.40005 0 90)
			(size 0 0)
			(layers "F.Cu" "F.Mask" "F.Paste")
			(net "GND")
		)
	)
	(footprint ""
		(layer "F.Cu")
		(at 95.926656 -4.605274 -90)
		(property "Reference" "J19"
			(at 1.049274 -2.779014 90)
			(unlocked yes)
			(layer "F.SilkS")
			(effects
				(font
					(size 0.7874 0.5842)
					(thickness 0.1524)
				)
				(justify left)
			)
		)
		(property "Value" ""
			(at 0 0 270)
			(layer "F.Fab")
			(effects
				(font
					(size 1.27 1.27)
				)
			)
		)
		(duplicate_pad_numbers_are_jumpers no)
		(fp_line
			(start -1.2192 2.1082)
			(end -1.2192 -2.1082)
			(stroke
				(width 0.1524)
				(type default)
			)
			(layer "F.SilkS")
		)
		(fp_line
			(start 1.2192 2.1082)
			(end -1.2192 2.1082)
			(stroke
				(width 0.1524)
				(type default)
			)
			(layer "F.SilkS")
		)
		(fp_line
			(start 1.2192 0.810514)
			(end 1.2192 2.1082)
			(stroke
				(width 0.1524)
				(type default)
			)
			(layer "F.SilkS")
		)
		(fp_line
			(start -1.2192 -2.1082)
			(end 1.2192 -2.1082)
			(stroke
				(width 0.1524)
				(type default)
			)
			(layer "F.SilkS")
		)
		(fp_line
			(start 1.2192 -2.1082)
			(end 1.2192 -0.825246)
			(stroke
				(width 0.1524)
				(type default)
			)
			(layer "F.SilkS")
		)
		(pad "" np_thru_hole circle
			(at -2.8829 -1.27 180)
			(size 1.0414 1.0414)
			(drill 1.0414)
			(layers "*.Cu" "*.Mask")
			(clearance 0.381)
			(thermal_gap 0.381)
		)
		(pad "" np_thru_hole circle
			(at -2.8829 1.27 180)
			(size 1.0414 1.0414)
			(drill 1.0414)
			(layers "*.Cu" "*.Mask")
			(clearance 0.381)
			(thermal_gap 0.381)
		)
		(pad "" np_thru_hole circle
			(at 3.4671 -1.27 180)
			(size 1.0414 1.0414)
			(drill 1.0414)
			(layers "*.Cu" "*.Mask")
			(clearance 0.381)
			(thermal_gap 0.381)
		)
		(pad "" np_thru_hole circle
			(at 3.4671 1.27 180)
			(size 1.0414 1.0414)
			(drill 1.0414)
			(layers "*.Cu" "*.Mask")
			(clearance 0.381)
			(thermal_gap 0.381)
		)
		(pad "1" smd rect
			(at 0.8255 -0.249936 180)
			(size 0.3048 0.508)
			(layers "F.Cu" "F.Mask" "F.Paste")
			(net "85_5INCH_IN4_DP")
		)
		(pad "2" smd rect
			(at 0.8255 0.249936 180)
			(size 0.3048 0.508)
			(layers "F.Cu" "F.Mask" "F.Paste")
			(net "85_5INCH_IN4_DN")
		)
		(pad "3" smd circle
			(at 0 0 270)
			(size 0 0)
			(layers "F.Cu" "F.Mask" "F.Paste")
			(net "GND_P1")
		)
		(zone
			(layer "F.Cu")
			(hatch none 0.5)
			(connect_pads
				(clearance 0)
			)
			(min_thickness 0.25)
			(keepout
				(tracks not_allowed)
				(vias allowed)
				(pads allowed)
				(copperpour not_allowed)
				(footprints allowed)
			)
			(placement
				(enabled no)
				(sheetname "")
			)
			(fill
				(thermal_gap 0.5)
				(thermal_bridge_width 0.5)
				(island_removal_mode 0)
			)
			(polygon
				(pts
					(xy 96.475296 -3.487674) (xy 96.379792 -3.487674) (xy 96.379792 -4.084574) (xy 95.973392 -4.084574)
					(xy 95.973392 -3.487674) (xy 95.87992 -3.487674) (xy 95.87992 -4.084574) (xy 95.47352 -4.084574)
					(xy 95.47352 -3.487674) (xy 95.378016 -3.487674) (xy 95.378016 -4.186174) (xy 96.475296 -4.186174)
				)
			)
		)
		(zone
			(layers "F.Cu" "B.Cu" "In1.Cu" "In2.Cu" "In3.Cu" "In4.Cu" "In5.Cu" "In6.Cu"
				"In7.Cu" "In8.Cu" "In9.Cu" "In10.Cu"
			)
			(hatch none 0.5)
			(connect_pads
				(clearance 0)
			)
			(min_thickness 0.25)
			(keepout
				(tracks not_allowed)
				(vias allowed)
				(pads allowed)
				(copperpour not_allowed)
				(footprints allowed)
			)
			(placement
				(enabled no)
				(sheetname "")
			)
			(fill
				(thermal_gap 0.5)
				(thermal_bridge_width 0.5)
				(island_removal_mode 0)
			)
			(polygon
				(pts
					(arc
						(start 95.583756 -7.488174)
						(mid 93.729556 -7.488174)
						(end 95.583756 -7.488174)
					)
				)
			)
		)
		(zone
			(layers "F.Cu" "B.Cu" "In1.Cu" "In2.Cu" "In3.Cu" "In4.Cu" "In5.Cu" "In6.Cu"
				"In7.Cu" "In8.Cu" "In9.Cu" "In10.Cu"
			)
			(hatch none 0.5)
			(connect_pads
				(clearance 0)
			)
			(min_thickness 0.25)
			(keepout
				(tracks not_allowed)
				(vias allowed)
				(pads allowed)
				(copperpour not_allowed)
				(footprints allowed)
			)
			(placement
				(enabled no)
				(sheetname "")
			)
			(fill
				(thermal_gap 0.5)
				(thermal_bridge_width 0.5)
				(island_removal_mode 0)
			)
			(polygon
				(pts
					(arc
						(start 95.583756 -1.138174)
						(mid 93.729556 -1.138174)
						(end 95.583756 -1.138174)
					)
				)
			)
		)
		(zone
			(layers "F.Cu" "B.Cu" "In1.Cu" "In2.Cu" "In3.Cu" "In4.Cu" "In5.Cu" "In6.Cu"
				"In7.Cu" "In8.Cu" "In9.Cu" "In10.Cu"
			)
			(hatch none 0.5)
			(connect_pads
				(clearance 0)
			)
			(min_thickness 0.25)
			(keepout
				(tracks not_allowed)
				(vias allowed)
				(pads allowed)
				(copperpour not_allowed)
				(footprints allowed)
			)
			(placement
				(enabled no)
				(sheetname "")
			)
			(fill
				(thermal_gap 0.5)
				(thermal_bridge_width 0.5)
				(island_removal_mode 0)
			)
			(polygon
				(pts
					(arc
						(start 98.123756 -7.488174)
						(mid 96.269556 -7.488174)
						(end 98.123756 -7.488174)
					)
				)
			)
		)
		(zone
			(layers "F.Cu" "B.Cu" "In1.Cu" "In2.Cu" "In3.Cu" "In4.Cu" "In5.Cu" "In6.Cu"
				"In7.Cu" "In8.Cu" "In9.Cu" "In10.Cu"
			)
			(hatch none 0.5)
			(connect_pads
				(clearance 0)
			)
			(min_thickness 0.25)
			(keepout
				(tracks not_allowed)
				(vias allowed)
				(pads allowed)
				(copperpour not_allowed)
				(footprints allowed)
			)
			(placement
				(enabled no)
				(sheetname "")
			)
			(fill
				(thermal_gap 0.5)
				(thermal_bridge_width 0.5)
				(island_removal_mode 0)
			)
			(polygon
				(pts
					(arc
						(start 98.123756 -1.138174)
						(mid 96.269556 -1.138174)
						(end 98.123756 -1.138174)
					)
				)
			)
		)
	)
	(footprint ""
		(layer "F.Cu")
		(at 50.79619 -34.637726 90)
		(property "Reference" "R148"
			(at 0 0 90)
			(layer "F.SilkS")
			(hide yes)
			(effects
				(font
					(size 1.27 1.27)
				)
			)
		)
		(property "Value" ""
			(at 0 0 90)
			(layer "F.Fab")
			(effects
				(font
					(size 1.27 1.27)
				)
			)
		)
		(duplicate_pad_numbers_are_jumpers no)
		(fp_line
			(start 0.7874 -0.4064)
			(end 0.7874 0.4064)
			(stroke
				(width 0.1524)
				(type default)
			)
			(layer "F.SilkS")
		)
		(fp_line
			(start -0.7874 -0.4064)
			(end 0.7874 -0.4064)
			(stroke
				(width 0.1524)
				(type default)
			)
			(layer "F.SilkS")
		)
		(fp_line
			(start 0.7874 0.4064)
			(end -0.7874 0.4064)
			(stroke
				(width 0.1524)
				(type default)
			)
			(layer "F.SilkS")
		)
		(fp_line
			(start -0.7874 0.4064)
			(end -0.7874 -0.4064)
			(stroke
				(width 0.1524)
				(type default)
			)
			(layer "F.SilkS")
		)
		(fp_line
			(start -0.12065 -0.305054)
			(end -0.12065 -0.2794)
			(stroke
				(width 0.1)
				(type default)
			)
			(layer "F.Fab")
		)
		(fp_line
			(start -0.67945 -0.305054)
			(end -0.12065 -0.305054)
			(stroke
				(width 0.1)
				(type default)
			)
			(layer "F.Fab")
		)
		(fp_line
			(start 0.67945 -0.3048)
			(end 0.67945 0.3048)
			(stroke
				(width 0.1)
				(type default)
			)
			(layer "F.Fab")
		)
		(fp_line
			(start 0.12065 -0.3048)
			(end 0.67945 -0.3048)
			(stroke
				(width 0.1)
				(type default)
			)
			(layer "F.Fab")
		)
		(fp_line
			(start 0.12065 -0.2794)
			(end 0.12065 -0.3048)
			(stroke
				(width 0.1)
				(type default)
			)
			(layer "F.Fab")
		)
		(fp_line
			(start -0.12065 -0.2794)
			(end 0.12065 -0.2794)
			(stroke
				(width 0.1)
				(type default)
			)
			(layer "F.Fab")
		)
		(fp_line
			(start 0.120396 0.2794)
			(end -0.12065 0.2794)
			(stroke
				(width 0.1)
				(type default)
			)
			(layer "F.Fab")
		)
		(fp_line
			(start -0.12065 0.2794)
			(end -0.12065 0.3048)
			(stroke
				(width 0.1)
				(type default)
			)
			(layer "F.Fab")
		)
		(fp_line
			(start 0.67945 0.3048)
			(end 0.120396 0.3048)
			(stroke
				(width 0.1)
				(type default)
			)
			(layer "F.Fab")
		)
		(fp_line
			(start 0.120396 0.3048)
			(end 0.120396 0.2794)
			(stroke
				(width 0.1)
				(type default)
			)
			(layer "F.Fab")
		)
		(fp_line
			(start -0.12065 0.3048)
			(end -0.67945 0.3048)
			(stroke
				(width 0.1)
				(type default)
			)
			(layer "F.Fab")
		)
		(fp_line
			(start -0.67945 0.3048)
			(end -0.67945 -0.305054)
			(stroke
				(width 0.1)
				(type default)
			)
			(layer "F.Fab")
		)
		(pad "1" smd circle
			(at -0.40005 0 90)
			(size 0 0)
			(layers "F.Cu" "F.Mask" "F.Paste")
			(net "SGPIO_CLK_1")
		)
		(pad "2" smd circle
			(at 0.40005 0 90)
			(size 0 0)
			(layers "F.Cu" "F.Mask" "F.Paste")
			(net "SGPIO_BMC_M1_CLK")
		)
	)
	(footprint ""
		(layer "F.Cu")
		(at 82.00009 -2.94005)
		(property "Reference" "SW7"
			(at -5.2705 -5.448554 0)
			(unlocked yes)
			(layer "F.SilkS")
			(effects
				(font
					(size 0.7874 0.5842)
					(thickness 0.1524)
				)
				(justify left)
			)
		)
		(property "Value" ""
			(at 0 0 0)
			(layer "F.Fab")
			(effects
				(font
					(size 1.27 1.27)
				)
			)
		)
		(duplicate_pad_numbers_are_jumpers no)
		(fp_line
			(start -3.700018 -4.549902)
			(end -3.700018 -2.51206)
			(stroke
				(width 0.1524)
				(type default)
			)
			(layer "F.SilkS")
		)
		(fp_line
			(start -3.700018 -0.98806)
			(end -3.700018 -0.88646)
			(stroke
				(width 0.1524)
				(type default)
			)
			(layer "F.SilkS")
		)
		(fp_line
			(start -3.700018 1.39954)
			(end -3.700018 1.549908)
			(stroke
				(width 0.1524)
				(type default)
			)
			(layer "F.SilkS")
		)
		(fp_line
			(start -3.700018 1.549908)
			(end -1.75006 1.549908)
			(stroke
				(width 0.1524)
				(type default)
			)
			(layer "F.SilkS")
		)
		(fp_line
			(start -3.1496 -4.549902)
			(end -3.700018 -4.549902)
			(stroke
				(width 0.1524)
				(type default)
			)
			(layer "F.SilkS")
		)
		(fp_line
			(start -1.75006 1.549908)
			(end -1.75006 4.549902)
			(stroke
				(width 0.1524)
				(type default)
			)
			(layer "F.SilkS")
		)
		(fp_line
			(start -1.75006 4.549902)
			(end 1.75006 4.549902)
			(stroke
				(width 0.1524)
				(type default)
			)
			(layer "F.SilkS")
		)
		(fp_line
			(start 1.3716 -4.549902)
			(end -1.3716 -4.549902)
			(stroke
				(width 0.1524)
				(type default)
			)
			(layer "F.SilkS")
		)
		(fp_line
			(start 1.75006 1.549908)
			(end 3.700018 1.549908)
			(stroke
				(width 0.1524)
				(type default)
			)
			(layer "F.SilkS")
		)
		(fp_line
			(start 1.75006 4.549902)
			(end 1.75006 1.549908)
			(stroke
				(width 0.1524)
				(type default)
			)
			(layer "F.SilkS")
		)
		(fp_line
			(start 3.700018 -4.549902)
			(end 3.1496 -4.549902)
			(stroke
				(width 0.1524)
				(type default)
			)
			(layer "F.SilkS")
		)
		(fp_line
			(start 3.700018 -2.51206)
			(end 3.700018 -4.549902)
			(stroke
				(width 0.1524)
				(type default)
			)
			(layer "F.SilkS")
		)
		(fp_line
			(start 3.700018 -0.88646)
			(end 3.700018 -0.98806)
			(stroke
				(width 0.1524)
				(type default)
			)
			(layer "F.SilkS")
		)
		(fp_line
			(start 3.700018 1.549908)
			(end 3.700018 1.39954)
			(stroke
				(width 0.1524)
				(type default)
			)
			(layer "F.SilkS")
		)
		(fp_poly
			(pts
				(xy -3.883914 -4.043934) (xy -5.310886 -3.330448) (xy -5.310886 -4.75742)
			)
			(stroke
				(width 0)
				(type default)
			)
			(fill yes)
			(layer "F.SilkS")
		)
		(fp_line
			(start -3.700018 -4.549902)
			(end -3.700018 1.549908)
			(stroke
				(width 0.1)
				(type default)
			)
			(layer "F.Fab")
		)
		(fp_line
			(start -3.700018 1.549908)
			(end -1.75006 1.549908)
			(stroke
				(width 0.1)
				(type default)
			)
			(layer "F.Fab")
		)
		(fp_line
			(start -1.75006 1.549908)
			(end -1.75006 4.549902)
			(stroke
				(width 0.1)
				(type default)
			)
			(layer "F.Fab")
		)
		(fp_line
			(start -1.75006 4.549902)
			(end 1.75006 4.549902)
			(stroke
				(width 0.1)
				(type default)
			)
			(layer "F.Fab")
		)
		(fp_line
			(start 1.75006 1.549908)
			(end 3.700018 1.549908)
			(stroke
				(width 0.1)
				(type default)
			)
			(layer "F.Fab")
		)
		(fp_line
			(start 1.75006 4.549902)
			(end 1.75006 1.549908)
			(stroke
				(width 0.1)
				(type default)
			)
			(layer "F.Fab")
		)
		(fp_line
			(start 3.700018 -4.549902)
			(end -3.700018 -4.549902)
			(stroke
				(width 0.1)
				(type default)
			)
			(layer "F.Fab")
		)
		(fp_line
			(start 3.700018 1.549908)
			(end 3.700018 -4.549902)
			(stroke
				(width 0.1)
				(type default)
			)
			(layer "F.Fab")
		)
		(fp_poly
			(pts
				(xy -3.883914 -4.043934) (xy -5.310886 -3.330448) (xy -5.310886 -4.75742)
			)
			(stroke
				(width 0)
				(type default)
			)
			(fill yes)
			(layer "F.Fab")
		)
		(pad "" np_thru_hole circle
			(at -3.50012 -1.75006)
			(size 0.9144 0.9144)
			(drill 0.9144)
			(layers "*.Cu" "*.Mask")
			(clearance 0.381)
			(thermal_gap 0.381)
		)
		(pad "" np_thru_hole circle
			(at 3.50012 -1.75006)
			(size 0.9144 0.9144)
			(drill 0.9144)
			(layers "*.Cu" "*.Mask")
			(clearance 0.381)
			(thermal_gap 0.381)
		)
		(pad "1" smd rect
			(at -2.249932 -4.05003)
			(size 1.4986 2.0066)
			(layers "F.Cu" "F.Mask" "F.Paste")
			(net "GND")
		)
		(pad "2" smd rect
			(at 2.249932 -4.05003)
			(size 1.4986 2.0066)
			(layers "F.Cu" "F.Mask" "F.Paste")
			(net "REAR_ID_RST_BTN_N")
		)
		(pad "3" smd rect
			(at -4.19989 0.249936)
			(size 2.0066 2.0066)
			(layers "F.Cu" "F.Mask" "F.Paste")
			(net "GND")
		)
		(pad "4" smd rect
			(at 4.19989 0.249936)
			(size 2.0066 2.0066)
			(layers "F.Cu" "F.Mask" "F.Paste")
			(net "GND")
		)
		(zone
			(layers "F.Cu" "B.Cu" "In1.Cu" "In2.Cu" "In3.Cu" "In4.Cu" "In5.Cu" "In6.Cu"
				"In7.Cu" "In8.Cu" "In9.Cu" "In10.Cu"
			)
			(hatch none 0.5)
			(connect_pads
				(clearance 0)
			)
			(min_thickness 0.25)
			(keepout
				(tracks not_allowed)
				(vias allowed)
				(pads allowed)
				(copperpour not_allowed)
				(footprints allowed)
			)
			(placement
				(enabled no)
				(sheetname "")
			)
			(fill
				(thermal_gap 0.5)
				(thermal_bridge_width 0.5)
				(island_removal_mode 0)
			)
			(polygon
				(pts
					(arc
						(start 79.363824 -4.69011)
						(mid 77.636116 -4.69011)
						(end 79.363824 -4.69011)
					)
				)
			)
		)
		(zone
			(layers "F.Cu" "B.Cu" "In1.Cu" "In2.Cu" "In3.Cu" "In4.Cu" "In5.Cu" "In6.Cu"
				"In7.Cu" "In8.Cu" "In9.Cu" "In10.Cu"
			)
			(hatch none 0.5)
			(connect_pads
				(clearance 0)
			)
			(min_thickness 0.25)
			(keepout
				(tracks not_allowed)
				(vias allowed)
				(pads allowed)
				(copperpour not_allowed)
				(footprints allowed)
			)
			(placement
				(enabled no)
				(sheetname "")
			)
			(fill
				(thermal_gap 0.5)
				(thermal_bridge_width 0.5)
				(island_removal_mode 0)
			)
			(polygon
				(pts
					(arc
						(start 86.36381 -4.69011)
						(mid 84.63661 -4.69011)
						(end 86.36381 -4.69011)
					)
				)
			)
		)
	)
)
